(kicad_pcb
	(version 20260206)
	(generator "pcbnew")
	(generator_version "10.0")
	(general
		(thickness 1.6)
		(legacy_teardrops no)
	)
	(paper "A4")
	(title_block
		(title "baseboard — 13948-1b.1110WZS1818.brd")
		(comment 1 "Honey Badger (Wiwynn) / footprints 1763-1767 of 2523")
	)
	(layers
		(0 "F.Cu" signal "TOP")
		(4 "In1.Cu" signal "L2GND")
		(6 "In2.Cu" signal "L3")
		(8 "In3.Cu" signal "L4VCC")
		(10 "In4.Cu" signal "L5VCC")
		(12 "In5.Cu" signal "L6")
		(14 "In6.Cu" signal "L7GND")
		(2 "B.Cu" signal "BOTTOM")
		(9 "F.Adhes" user "F.Adhesive")
		(11 "B.Adhes" user "B.Adhesive")
		(13 "F.Paste" user "Package Geometry/Pastemask Top")
		(15 "B.Paste" user "Package Geometry/Pastemask Bottom")
		(5 "F.SilkS" user "Ref Des/Silkscreen Top")
		(7 "B.SilkS" user "Ref Des/Silkscreen Bottom")
		(1 "F.Mask" user "Board Geometry/Soldermask Top")
		(3 "B.Mask" user "Board Geometry/Soldermask Bottom")
		(17 "Dwgs.User" user "User.Drawings")
		(19 "Cmts.User" user "User.Comments")
		(21 "Eco1.User" user "User.Eco1")
		(23 "Eco2.User" user "User.Eco2")
		(25 "Edge.Cuts" user "Board Geometry/Outline")
		(27 "Margin" user)
		(31 "F.CrtYd" user "Package Geometry/Place Bound Top")
		(29 "B.CrtYd" user "Package Geometry/Place Bound Bottom")
		(35 "F.Fab" user "Ref Des/Assembly Top")
		(33 "B.Fab" user "Ref Des/Assembly Bottom")
	)
	(footprint ""
		(layer "F.Cu")
		(at 108.540042 -2.029968 90)
		(property "Reference" "LED4"
			(at 0 0 90)
			(layer "F.SilkS")
			(hide yes)
			(effects
				(font
					(size 1.27 1.27)
				)
			)
		)
		(property "Value" "LED-B-77-GP-U3"
			(at -0.7112 -3.6068 90)
			(unlocked yes)
			(layer "F.Fab")
			(hide yes)
			(effects
				(font
					(size 1.016 1.016)
					(thickness 0.1524)
				)
			)
		)
		(property "Device Type" "LED3020AK-U2H44"
			(at -0.7112 -5.1308 90)
			(unlocked yes)
			(layer "F.Fab")
			(hide yes)
			(effects
				(font
					(size 1.016 1.016)
					(thickness 0.1524)
				)
			)
		)
		(duplicate_pad_numbers_are_jumpers no)
		(fp_line
			(start 0.8382 -2.4003)
			(end -0.8382 -2.4003)
			(stroke
				(width 0.1524)
				(type default)
			)
			(layer "F.SilkS")
		)
		(fp_line
			(start -0.8382 -2.4003)
			(end -0.8382 -1.31445)
			(stroke
				(width 0.1524)
				(type default)
			)
			(layer "F.SilkS")
		)
		(fp_line
			(start -0.8382 1.31445)
			(end -0.8382 2.4003)
			(stroke
				(width 0.1524)
				(type default)
			)
			(layer "F.SilkS")
		)
		(fp_line
			(start 0.8382 2.4003)
			(end 0.8382 -2.4003)
			(stroke
				(width 0.1524)
				(type default)
			)
			(layer "F.SilkS")
		)
		(fp_line
			(start -0.8382 2.4003)
			(end 0.8382 2.4003)
			(stroke
				(width 0.1524)
				(type default)
			)
			(layer "F.SilkS")
		)
		(fp_line
			(start 0.889 2.5273)
			(end -0.889 2.5273)
			(stroke
				(width 0.4064)
				(type default)
			)
			(layer "F.SilkS")
		)
		(fp_arc
			(start -0.8382 1.31445)
			(mid -1.85412 0)
			(end -0.8382 -1.31445)
			(stroke
				(width 0.1524)
				(type default)
			)
			(layer "F.SilkS")
		)
		(fp_poly
			(pts
				(xy -1.0922 2.6543) (xy -1.0922 1.49606) (xy -1.15189 1.4732) (xy -1.27254 1.41351) (xy -1.38557 1.34493)
				(xy -1.49098 1.26873) (xy -1.59258 1.18237) (xy -1.68656 1.08712) (xy -1.77165 0.98552) (xy -1.84785 0.87757)
				(xy -1.91516 0.76454) (xy -1.97358 0.64262) (xy -2.02057 0.5207) (xy -2.05867 0.3937) (xy -2.08534 0.26416)
				(xy -2.10185 0.13335) (xy -2.1082 0) (xy -2.10185 -0.13335) (xy -2.08534 -0.26416) (xy -2.05867 -0.3937)
				(xy -2.02057 -0.5207) (xy -1.97358 -0.64262) (xy -1.91516 -0.76454) (xy -1.84785 -0.87757) (xy -1.77165 -0.98552)
				(xy -1.68656 -1.08712) (xy -1.59258 -1.18237) (xy -1.49098 -1.26873) (xy -1.38557 -1.34493) (xy -1.27254 -1.41351)
				(xy -1.15189 -1.4732) (xy -1.0922 -1.49606) (xy -1.0922 -2.6543) (xy 1.0922 -2.6543) (xy 1.0922 2.6543)
			)
			(stroke
				(width 0)
				(type default)
			)
			(fill no)
			(layer "F.CrtYd")
		)
		(fp_poly
			(pts
				(xy -1.0922 2.6543) (xy -1.0922 1.49606) (xy -1.15189 1.4732) (xy -1.27254 1.41351) (xy -1.38557 1.34493)
				(xy -1.49098 1.26873) (xy -1.59258 1.18237) (xy -1.68656 1.08712) (xy -1.77165 0.98552) (xy -1.84785 0.87757)
				(xy -1.91516 0.76454) (xy -1.97358 0.64262) (xy -2.02057 0.5207) (xy -2.05867 0.3937) (xy -2.08534 0.26416)
				(xy -2.10185 0.13335) (xy -2.1082 0) (xy -2.10185 -0.13335) (xy -2.08534 -0.26416) (xy -2.05867 -0.3937)
				(xy -2.02057 -0.5207) (xy -1.97358 -0.64262) (xy -1.91516 -0.76454) (xy -1.84785 -0.87757) (xy -1.77165 -0.98552)
				(xy -1.68656 -1.08712) (xy -1.59258 -1.18237) (xy -1.49098 -1.26873) (xy -1.38557 -1.34493) (xy -1.27254 -1.41351)
				(xy -1.15189 -1.4732) (xy -1.0922 -1.49606) (xy -1.0922 -2.6543) (xy 1.0922 -2.6543) (xy 1.0922 2.6543)
			)
			(stroke
				(width 0)
				(type default)
			)
			(fill no)
			(layer "F.Fab")
		)
		(pad "A" smd rect
			(at 0 -1.57099 90)
			(size 1.143 1.143)
			(layers "F.Cu" "F.Mask" "F.Paste")
			(net "ENCLO_LED_RED_R")
		)
		(pad "K" smd rect
			(at 0 1.57099 90)
			(size 1.143 1.143)
			(layers "F.Cu" "F.Mask" "F.Paste")
			(net "ENCLO_LED_RED_D1")
		)
	)
	(footprint ""
		(layer "F.Cu")
		(at 216.154 -97.79 -90)
		(property "Reference" "PC138"
			(at 0 0 270)
			(layer "F.SilkS")
			(hide yes)
			(effects
				(font
					(size 1.27 1.27)
				)
			)
		)
		(property "Value" "SCD1U16V2KX-3GP"
			(at 1.1811 -2.7051 270)
			(unlocked yes)
			(layer "F.Fab")
			(hide yes)
			(effects
				(font
					(size 1.016 1.016)
					(thickness 0.1524)
				)
			)
		)
		(property "Device Type" "C402H22"
			(at 1.1811 -4.2291 270)
			(unlocked yes)
			(layer "F.Fab")
			(hide yes)
			(effects
				(font
					(size 1.016 1.016)
					(thickness 0.1524)
				)
			)
		)
		(duplicate_pad_numbers_are_jumpers no)
		(fp_rect
			(start -0.4318 0.9525)
			(end 0.4318 -0.9525)
			(stroke
				(width 0)
				(type default)
			)
			(fill no)
			(layer "F.CrtYd")
		)
		(fp_rect
			(start -0.4318 0.9525)
			(end 0.4318 -0.9525)
			(stroke
				(width 0)
				(type default)
			)
			(fill no)
			(layer "F.Fab")
		)
		(pad "1" smd custom
			(at 0 -0.4445 270)
			(size 0.1524 0.1524)
			(layers "F.Cu" "F.Mask" "F.Paste")
			(net "TPS74801_P1V5_C_IN")
			(options
				(clearance outline)
				(anchor circle)
			)
			(primitives
				(gr_poly
					(pts
						(arc
							(start 0.3048 -0.2032)
							(mid 0.275042 -0.275042)
							(end 0.2032 -0.3048)
						)
						(arc
							(start -0.2032 -0.3048)
							(mid -0.275042 -0.275042)
							(end -0.3048 -0.2032)
						)
						(arc
							(start -0.3048 0.2032)
							(mid -0.275042 0.275042)
							(end -0.2032 0.3048)
						)
						(arc
							(start 0.2032 0.3048)
							(mid 0.275042 0.275042)
							(end 0.3048 0.2032)
						)
					)
					(width 0)
					(fill yes)
				)
			)
		)
		(pad "2" smd custom
			(at 0 0.4445 270)
			(size 0.1524 0.1524)
			(layers "F.Cu" "F.Mask" "F.Paste")
			(net "GND")
			(options
				(clearance outline)
				(anchor circle)
			)
			(primitives
				(gr_poly
					(pts
						(arc
							(start 0.3048 -0.2032)
							(mid 0.275042 -0.275042)
							(end 0.2032 -0.3048)
						)
						(arc
							(start -0.2032 -0.3048)
							(mid -0.275042 -0.275042)
							(end -0.3048 -0.2032)
						)
						(arc
							(start -0.3048 0.2032)
							(mid -0.275042 0.275042)
							(end -0.2032 0.3048)
						)
						(arc
							(start 0.2032 0.3048)
							(mid 0.275042 0.275042)
							(end 0.3048 0.2032)
						)
					)
					(width 0)
					(fill yes)
				)
			)
		)
	)
	(footprint ""
		(layer "F.Cu")
		(at 173.325028 -31.608268)
		(property "Reference" "R385"
			(at 0 0 0)
			(layer "F.SilkS")
			(hide yes)
			(effects
				(font
					(size 1.27 1.27)
				)
			)
		)
		(property "Value" "0R2J-2-GP"
			(at 0.064008 -3.993896 0)
			(unlocked yes)
			(layer "F.Fab")
			(hide yes)
			(effects
				(font
					(size 1.016 1.016)
					(thickness 0.1524)
				)
			)
		)
		(property "Device Type" "R402H16"
			(at 0.064008 -5.517896 0)
			(unlocked yes)
			(layer "F.Fab")
			(hide yes)
			(effects
				(font
					(size 1.016 1.016)
					(thickness 0.1524)
				)
			)
		)
		(duplicate_pad_numbers_are_jumpers no)
		(fp_line
			(start -0.508 -0.9398)
			(end -0.508 0.9398)
			(stroke
				(width 0.1524)
				(type default)
			)
			(layer "F.SilkS")
		)
		(fp_line
			(start 0.508 -0.9398)
			(end -0.508 -0.9398)
			(stroke
				(width 0.1524)
				(type default)
			)
			(layer "F.SilkS")
		)
		(fp_rect
			(start -0.508 0.9398)
			(end 0.508 -0.9398)
			(stroke
				(width 0)
				(type default)
			)
			(fill no)
			(layer "F.CrtYd")
		)
		(fp_rect
			(start -0.508 0.9398)
			(end 0.508 -0.9398)
			(stroke
				(width 0)
				(type default)
			)
			(fill no)
			(layer "F.Fab")
		)
		(pad "1" smd custom
			(at 0 -0.4445)
			(size 0.1397 0.1397)
			(layers "F.Cu" "F.Mask" "F.Paste")
			(net "BCM5221_MB_RX_DP")
			(options
				(clearance outline)
				(anchor circle)
			)
			(primitives
				(gr_poly
					(pts
						(arc
							(start -0.1778 -0.2794)
							(mid -0.249642 -0.249642)
							(end -0.2794 -0.1778)
						)
						(arc
							(start -0.2794 0.1778)
							(mid -0.249642 0.249642)
							(end -0.1778 0.2794)
						)
						(arc
							(start 0.1778 0.2794)
							(mid 0.249642 0.249642)
							(end 0.2794 0.1778)
						)
						(arc
							(start 0.2794 -0.1778)
							(mid 0.249642 -0.249642)
							(end 0.1778 -0.2794)
						)
					)
					(width 0)
					(fill yes)
				)
			)
		)
		(pad "2" smd custom
			(at 0 0.4445)
			(size 0.1397 0.1397)
			(layers "F.Cu" "F.Mask" "F.Paste")
			(net "BCM5221_RX_C_DP")
			(options
				(clearance outline)
				(anchor circle)
			)
			(primitives
				(gr_poly
					(pts
						(arc
							(start -0.1778 -0.2794)
							(mid -0.249642 -0.249642)
							(end -0.2794 -0.1778)
						)
						(arc
							(start -0.2794 0.1778)
							(mid -0.249642 0.249642)
							(end -0.1778 0.2794)
						)
						(arc
							(start 0.1778 0.2794)
							(mid 0.249642 0.249642)
							(end 0.2794 0.1778)
						)
						(arc
							(start 0.2794 -0.1778)
							(mid 0.249642 -0.249642)
							(end 0.1778 -0.2794)
						)
					)
					(width 0)
					(fill yes)
				)
			)
		)
	)
	(footprint ""
		(layer "F.Cu")
		(at 337.557872 -171.395136)
		(property "Reference" "R276"
			(at 0 0 0)
			(layer "F.SilkS")
			(hide yes)
			(effects
				(font
					(size 1.27 1.27)
				)
			)
		)
		(property "Value" "10KR2F-2-GP"
			(at 0.064008 -3.993896 0)
			(unlocked yes)
			(layer "F.Fab")
			(hide yes)
			(effects
				(font
					(size 1.016 1.016)
					(thickness 0.1524)
				)
			)
		)
		(property "Device Type" "R402H16"
			(at 0.064008 -5.517896 0)
			(unlocked yes)
			(layer "F.Fab")
			(hide yes)
			(effects
				(font
					(size 1.016 1.016)
					(thickness 0.1524)
				)
			)
		)
		(duplicate_pad_numbers_are_jumpers no)
		(fp_line
			(start -0.508 -0.9398)
			(end -0.508 0.9398)
			(stroke
				(width 0.1524)
				(type default)
			)
			(layer "F.SilkS")
		)
		(fp_line
			(start 0.508 -0.9398)
			(end -0.508 -0.9398)
			(stroke
				(width 0.1524)
				(type default)
			)
			(layer "F.SilkS")
		)
		(fp_rect
			(start -0.508 0.9398)
			(end 0.508 -0.9398)
			(stroke
				(width 0)
				(type default)
			)
			(fill no)
			(layer "F.CrtYd")
		)
		(fp_rect
			(start -0.508 0.9398)
			(end 0.508 -0.9398)
			(stroke
				(width 0)
				(type default)
			)
			(fill no)
			(layer "F.Fab")
		)
		(pad "1" smd custom
			(at 0 -0.4445)
			(size 0.1397 0.1397)
			(layers "F.Cu" "F.Mask" "F.Paste")
			(net "P3V3_STBY")
			(options
				(clearance outline)
				(anchor circle)
			)
			(primitives
				(gr_poly
					(pts
						(arc
							(start -0.1778 -0.2794)
							(mid -0.249642 -0.249642)
							(end -0.2794 -0.1778)
						)
						(arc
							(start -0.2794 0.1778)
							(mid -0.249642 0.249642)
							(end -0.1778 0.2794)
						)
						(arc
							(start 0.1778 0.2794)
							(mid 0.249642 0.249642)
							(end 0.2794 0.1778)
						)
						(arc
							(start 0.2794 -0.1778)
							(mid 0.249642 -0.249642)
							(end 0.1778 -0.2794)
						)
					)
					(width 0)
					(fill yes)
				)
			)
		)
		(pad "2" smd custom
			(at 0 0.4445)
			(size 0.1397 0.1397)
			(layers "F.Cu" "F.Mask" "F.Paste")
			(net "BMC_UART_SWITCH_R")
			(options
				(clearance outline)
				(anchor circle)
			)
			(primitives
				(gr_poly
					(pts
						(arc
							(start -0.1778 -0.2794)
							(mid -0.249642 -0.249642)
							(end -0.2794 -0.1778)
						)
						(arc
							(start -0.2794 0.1778)
							(mid -0.249642 0.249642)
							(end -0.1778 0.2794)
						)
						(arc
							(start 0.1778 0.2794)
							(mid 0.249642 0.249642)
							(end 0.2794 0.1778)
						)
						(arc
							(start 0.2794 -0.1778)
							(mid 0.249642 -0.249642)
							(end 0.1778 -0.2794)
						)
					)
					(width 0)
					(fill yes)
				)
			)
		)
	)
	(footprint ""
		(layer "F.Cu")
		(at 175.949864 -34.997136 -90)
		(property "Reference" "R382"
			(at 0 0 270)
			(layer "F.SilkS")
			(hide yes)
			(effects
				(font
					(size 1.27 1.27)
				)
			)
		)
		(property "Value" "1K27R2D-GP"
			(at 0.064008 -3.993896 270)
			(unlocked yes)
			(layer "F.Fab")
			(hide yes)
			(effects
				(font
					(size 1.016 1.016)
					(thickness 0.1524)
				)
			)
		)
		(property "Device Type" "R402H16"
			(at 0.064008 -5.517896 270)
			(unlocked yes)
			(layer "F.Fab")
			(hide yes)
			(effects
				(font
					(size 1.016 1.016)
					(thickness 0.1524)
				)
			)
		)
		(duplicate_pad_numbers_are_jumpers no)
		(fp_line
			(start -0.508 -0.9398)
			(end -0.508 0.9398)
			(stroke
				(width 0.1524)
				(type default)
			)
			(layer "F.SilkS")
		)
		(fp_line
			(start 0.508 -0.9398)
			(end -0.508 -0.9398)
			(stroke
				(width 0.1524)
				(type default)
			)
			(layer "F.SilkS")
		)
		(fp_rect
			(start -0.508 0.9398)
			(end 0.508 -0.9398)
			(stroke
				(width 0)
				(type default)
			)
			(fill no)
			(layer "F.CrtYd")
		)
		(fp_rect
			(start -0.508 0.9398)
			(end 0.508 -0.9398)
			(stroke
				(width 0)
				(type default)
			)
			(fill no)
			(layer "F.Fab")
		)
		(pad "1" smd custom
			(at 0 -0.4445 270)
			(size 0.1397 0.1397)
			(layers "F.Cu" "F.Mask" "F.Paste")
			(net "BMC_PHY_RDAC")
			(options
				(clearance outline)
				(anchor circle)
			)
			(primitives
				(gr_poly
					(pts
						(arc
							(start -0.1778 -0.2794)
							(mid -0.249642 -0.249642)
							(end -0.2794 -0.1778)
						)
						(arc
							(start -0.2794 0.1778)
							(mid -0.249642 0.249642)
							(end -0.1778 0.2794)
						)
						(arc
							(start 0.1778 0.2794)
							(mid 0.249642 0.249642)
							(end 0.2794 0.1778)
						)
						(arc
							(start 0.2794 -0.1778)
							(mid 0.249642 -0.249642)
							(end 0.1778 -0.2794)
						)
					)
					(width 0)
					(fill yes)
				)
			)
		)
		(pad "2" smd custom
			(at 0 0.4445 270)
			(size 0.1397 0.1397)
			(layers "F.Cu" "F.Mask" "F.Paste")
			(net "GND")
			(options
				(clearance outline)
				(anchor circle)
			)
			(primitives
				(gr_poly
					(pts
						(arc
							(start -0.1778 -0.2794)
							(mid -0.249642 -0.249642)
							(end -0.2794 -0.1778)
						)
						(arc
							(start -0.2794 0.1778)
							(mid -0.249642 0.249642)
							(end -0.1778 0.2794)
						)
						(arc
							(start 0.1778 0.2794)
							(mid 0.249642 0.249642)
							(end 0.2794 0.1778)
						)
						(arc
							(start 0.2794 -0.1778)
							(mid 0.249642 -0.249642)
							(end 0.1778 -0.2794)
						)
					)
					(width 0)
					(fill yes)
				)
			)
		)
	)
)
